(kicad_pcb
	(version 20260206)
	(generator "pcbnew")
	(generator_version "10.0")
	(general
		(thickness 1.6)
		(legacy_teardrops no)
	)
	(paper "A4")
	(title_block
		(title "pdpb — Lightning_PDPB_BRD.brd")
		(comment 1 "Lightning (Wiwynn / Facebook NVMe JBOF) / footprints 1048-1054 of 1140")
	)
	(layers
		(0 "F.Cu" signal "TOP")
		(4 "In1.Cu" signal "L2GND")
		(6 "In2.Cu" signal "L3")
		(8 "In3.Cu" signal "L4VCC")
		(10 "In4.Cu" signal "L5VCC")
		(12 "In5.Cu" signal "L6")
		(14 "In6.Cu" signal "L7GND")
		(2 "B.Cu" signal "BOTTOM")
		(9 "F.Adhes" user "F.Adhesive")
		(11 "B.Adhes" user "B.Adhesive")
		(13 "F.Paste" user "Package Geometry/Pastemask Top")
		(15 "B.Paste" user "Package Geometry/Pastemask Bottom")
		(5 "F.SilkS" user "Ref Des/Silkscreen Top")
		(7 "B.SilkS" user "Ref Des/Silkscreen Bottom")
		(1 "F.Mask" user "Board Geometry/Soldermask Top")
		(3 "B.Mask" user "Board Geometry/Soldermask Bottom")
		(17 "Dwgs.User" user "User.Drawings")
		(19 "Cmts.User" user "User.Comments")
		(21 "Eco1.User" user "User.Eco1")
		(23 "Eco2.User" user "User.Eco2")
		(25 "Edge.Cuts" user "Board Geometry/Outline")
		(27 "Margin" user)
		(31 "F.CrtYd" user "Package Geometry/Place Bound Top")
		(29 "B.CrtYd" user "Package Geometry/Place Bound Bottom")
		(35 "F.Fab" user "Ref Des/Assembly Top")
		(33 "B.Fab" user "Ref Des/Assembly Bottom")
	)
	(footprint ""
		(layer "F.Cu")
		(at 78.994 -309.245 -90)
		(property "Reference" "C8914"
			(at 0 0 270)
			(layer "F.SilkS")
			(hide yes)
			(effects
				(font
					(size 1.27 1.27)
				)
			)
		)
		(property "Value" "SC10U25V3MX-GP"
			(at 0 -2.8194 270)
			(unlocked yes)
			(layer "F.Fab")
			(hide yes)
			(effects
				(font
					(size 1.016 1.016)
					(thickness 0.1524)
				)
			)
		)
		(property "Device Type" "C603H40"
			(at 0 -4.3434 270)
			(unlocked yes)
			(layer "F.Fab")
			(hide yes)
			(effects
				(font
					(size 1.016 1.016)
					(thickness 0.1524)
				)
			)
		)
		(duplicate_pad_numbers_are_jumpers no)
		(fp_line
			(start 0.508 0)
			(end -0.508 0)
			(stroke
				(width 0.2032)
				(type default)
			)
			(layer "F.SilkS")
		)
		(fp_rect
			(start -0.5842 1.3335)
			(end 0.5842 -1.3335)
			(stroke
				(width 0)
				(type default)
			)
			(fill no)
			(layer "F.CrtYd")
		)
		(fp_rect
			(start -0.5842 1.3335)
			(end 0.5842 -1.3335)
			(stroke
				(width 0)
				(type default)
			)
			(fill no)
			(layer "F.Fab")
		)
		(pad "1" smd custom
			(at 0 -0.762 270)
			(size 0.2159 0.2159)
			(layers "F.Cu" "F.Mask" "F.Paste")
			(net "VDD_DIFF_2")
			(options
				(clearance outline)
				(anchor circle)
			)
			(primitives
				(gr_poly
					(pts
						(arc
							(start -0.3302 -0.4318)
							(mid -0.402042 -0.402042)
							(end -0.4318 -0.3302)
						)
						(arc
							(start -0.4318 0.3302)
							(mid -0.402042 0.402042)
							(end -0.3302 0.4318)
						)
						(arc
							(start 0.3302 0.4318)
							(mid 0.402042 0.402042)
							(end 0.4318 0.3302)
						)
						(arc
							(start 0.4318 -0.3302)
							(mid 0.402042 -0.402042)
							(end 0.3302 -0.4318)
						)
					)
					(width 0)
					(fill yes)
				)
			)
		)
		(pad "2" smd custom
			(at 0 0.762 270)
			(size 0.2159 0.2159)
			(layers "F.Cu" "F.Mask" "F.Paste")
			(net "GND")
			(options
				(clearance outline)
				(anchor circle)
			)
			(primitives
				(gr_poly
					(pts
						(arc
							(start -0.3302 -0.4318)
							(mid -0.402042 -0.402042)
							(end -0.4318 -0.3302)
						)
						(arc
							(start -0.4318 0.3302)
							(mid -0.402042 0.402042)
							(end -0.3302 0.4318)
						)
						(arc
							(start 0.3302 0.4318)
							(mid 0.402042 0.402042)
							(end 0.4318 0.3302)
						)
						(arc
							(start 0.4318 -0.3302)
							(mid 0.402042 -0.402042)
							(end 0.3302 -0.4318)
						)
					)
					(width 0)
					(fill yes)
				)
			)
		)
	)
	(footprint ""
		(layer "F.Cu")
		(at 99.314 -313.817 180)
		(property "Reference" "R9101"
			(at 0 0 180)
			(layer "F.SilkS")
			(hide yes)
			(effects
				(font
					(size 1.27 1.27)
				)
			)
		)
		(property "Value" "27R2F-GP"
			(at 0.064008 -3.993896 180)
			(unlocked yes)
			(layer "F.Fab")
			(hide yes)
			(effects
				(font
					(size 1.016 1.016)
					(thickness 0.1524)
				)
			)
		)
		(property "Device Type" "R402H16"
			(at 0.064008 -5.517896 180)
			(unlocked yes)
			(layer "F.Fab")
			(hide yes)
			(effects
				(font
					(size 1.016 1.016)
					(thickness 0.1524)
				)
			)
		)
		(duplicate_pad_numbers_are_jumpers no)
		(fp_line
			(start 0.508 -0.9398)
			(end -0.508 -0.9398)
			(stroke
				(width 0.1524)
				(type default)
			)
			(layer "F.SilkS")
		)
		(fp_line
			(start -0.508 -0.9398)
			(end -0.508 0.9398)
			(stroke
				(width 0.1524)
				(type default)
			)
			(layer "F.SilkS")
		)
		(fp_rect
			(start -0.508 0.9398)
			(end 0.508 -0.9398)
			(stroke
				(width 0)
				(type default)
			)
			(fill no)
			(layer "F.CrtYd")
		)
		(fp_rect
			(start -0.508 0.9398)
			(end 0.508 -0.9398)
			(stroke
				(width 0)
				(type default)
			)
			(fill no)
			(layer "F.Fab")
		)
		(pad "1" smd custom
			(at 0 -0.4445 180)
			(size 0.1397 0.1397)
			(layers "F.Cu" "F.Mask" "F.Paste")
			(net "PE_CLK_100M_DR6_2_R_N")
			(options
				(clearance outline)
				(anchor circle)
			)
			(primitives
				(gr_poly
					(pts
						(arc
							(start -0.1778 -0.2794)
							(mid -0.249642 -0.249642)
							(end -0.2794 -0.1778)
						)
						(arc
							(start -0.2794 0.1778)
							(mid -0.249642 0.249642)
							(end -0.1778 0.2794)
						)
						(arc
							(start 0.1778 0.2794)
							(mid 0.249642 0.249642)
							(end 0.2794 0.1778)
						)
						(arc
							(start 0.2794 -0.1778)
							(mid 0.249642 -0.249642)
							(end 0.1778 -0.2794)
						)
					)
					(width 0)
					(fill yes)
				)
			)
		)
		(pad "2" smd custom
			(at 0 0.4445 180)
			(size 0.1397 0.1397)
			(layers "F.Cu" "F.Mask" "F.Paste")
			(net "PE_CLK100M_DR6_2_N")
			(options
				(clearance outline)
				(anchor circle)
			)
			(primitives
				(gr_poly
					(pts
						(arc
							(start -0.1778 -0.2794)
							(mid -0.249642 -0.249642)
							(end -0.2794 -0.1778)
						)
						(arc
							(start -0.2794 0.1778)
							(mid -0.249642 0.249642)
							(end -0.1778 0.2794)
						)
						(arc
							(start 0.1778 0.2794)
							(mid 0.249642 0.249642)
							(end 0.2794 0.1778)
						)
						(arc
							(start 0.2794 -0.1778)
							(mid 0.249642 -0.249642)
							(end 0.1778 -0.2794)
						)
					)
					(width 0)
					(fill yes)
				)
			)
		)
	)
	(footprint ""
		(layer "F.Cu")
		(at 24.003 -380.238 90)
		(property "Reference" "R330"
			(at 0 0 90)
			(layer "F.SilkS")
			(hide yes)
			(effects
				(font
					(size 1.27 1.27)
				)
			)
		)
		(property "Value" "0R2J-2-GP"
			(at 0.064008 -3.993896 90)
			(unlocked yes)
			(layer "F.Fab")
			(hide yes)
			(effects
				(font
					(size 1.016 1.016)
					(thickness 0.1524)
				)
			)
		)
		(property "Device Type" "R402H16"
			(at 0.064008 -5.517896 90)
			(unlocked yes)
			(layer "F.Fab")
			(hide yes)
			(effects
				(font
					(size 1.016 1.016)
					(thickness 0.1524)
				)
			)
		)
		(duplicate_pad_numbers_are_jumpers no)
		(fp_line
			(start 0.508 -0.9398)
			(end -0.508 -0.9398)
			(stroke
				(width 0.1524)
				(type default)
			)
			(layer "F.SilkS")
		)
		(fp_line
			(start -0.508 -0.9398)
			(end -0.508 0.9398)
			(stroke
				(width 0.1524)
				(type default)
			)
			(layer "F.SilkS")
		)
		(fp_rect
			(start -0.508 0.9398)
			(end 0.508 -0.9398)
			(stroke
				(width 0)
				(type default)
			)
			(fill no)
			(layer "F.CrtYd")
		)
		(fp_rect
			(start -0.508 0.9398)
			(end 0.508 -0.9398)
			(stroke
				(width 0)
				(type default)
			)
			(fill no)
			(layer "F.Fab")
		)
		(pad "1" smd custom
			(at 0 -0.4445 90)
			(size 0.1397 0.1397)
			(layers "F.Cu" "F.Mask" "F.Paste")
			(net "I2C_B_SDA")
			(options
				(clearance outline)
				(anchor circle)
			)
			(primitives
				(gr_poly
					(pts
						(arc
							(start -0.1778 -0.2794)
							(mid -0.249642 -0.249642)
							(end -0.2794 -0.1778)
						)
						(arc
							(start -0.2794 0.1778)
							(mid -0.249642 0.249642)
							(end -0.1778 0.2794)
						)
						(arc
							(start 0.1778 0.2794)
							(mid 0.249642 0.249642)
							(end 0.2794 0.1778)
						)
						(arc
							(start 0.2794 -0.1778)
							(mid 0.249642 -0.249642)
							(end 0.1778 -0.2794)
						)
					)
					(width 0)
					(fill yes)
				)
			)
		)
		(pad "2" smd custom
			(at 0 0.4445 90)
			(size 0.1397 0.1397)
			(layers "F.Cu" "F.Mask" "F.Paste")
			(net "TMP4_SDA")
			(options
				(clearance outline)
				(anchor circle)
			)
			(primitives
				(gr_poly
					(pts
						(arc
							(start -0.1778 -0.2794)
							(mid -0.249642 -0.249642)
							(end -0.2794 -0.1778)
						)
						(arc
							(start -0.2794 0.1778)
							(mid -0.249642 0.249642)
							(end -0.1778 0.2794)
						)
						(arc
							(start 0.1778 0.2794)
							(mid 0.249642 0.249642)
							(end 0.2794 0.1778)
						)
						(arc
							(start 0.2794 -0.1778)
							(mid 0.249642 -0.249642)
							(end 0.1778 -0.2794)
						)
					)
					(width 0)
					(fill yes)
				)
			)
		)
	)
	(footprint ""
		(layer "F.Cu")
		(at 217.043 -82.804 -90)
		(property "Reference" "R396"
			(at 0 0 270)
			(layer "F.SilkS")
			(hide yes)
			(effects
				(font
					(size 1.27 1.27)
				)
			)
		)
		(property "Value" "0R2J-2-GP"
			(at 0.064008 -3.993896 270)
			(unlocked yes)
			(layer "F.Fab")
			(hide yes)
			(effects
				(font
					(size 1.016 1.016)
					(thickness 0.1524)
				)
			)
		)
		(property "Device Type" "R402H16"
			(at 0.064008 -5.517896 270)
			(unlocked yes)
			(layer "F.Fab")
			(hide yes)
			(effects
				(font
					(size 1.016 1.016)
					(thickness 0.1524)
				)
			)
		)
		(duplicate_pad_numbers_are_jumpers no)
		(fp_line
			(start -0.508 -0.9398)
			(end -0.508 0.9398)
			(stroke
				(width 0.1524)
				(type default)
			)
			(layer "F.SilkS")
		)
		(fp_line
			(start 0.508 -0.9398)
			(end -0.508 -0.9398)
			(stroke
				(width 0.1524)
				(type default)
			)
			(layer "F.SilkS")
		)
		(fp_rect
			(start -0.508 0.9398)
			(end 0.508 -0.9398)
			(stroke
				(width 0)
				(type default)
			)
			(fill no)
			(layer "F.CrtYd")
		)
		(fp_rect
			(start -0.508 0.9398)
			(end 0.508 -0.9398)
			(stroke
				(width 0)
				(type default)
			)
			(fill no)
			(layer "F.Fab")
		)
		(pad "1" smd custom
			(at 0 -0.4445 270)
			(size 0.1397 0.1397)
			(layers "F.Cu" "F.Mask" "F.Paste")
			(net "SDA_DR4_R")
			(options
				(clearance outline)
				(anchor circle)
			)
			(primitives
				(gr_poly
					(pts
						(arc
							(start -0.1778 -0.2794)
							(mid -0.249642 -0.249642)
							(end -0.2794 -0.1778)
						)
						(arc
							(start -0.2794 0.1778)
							(mid -0.249642 0.249642)
							(end -0.1778 0.2794)
						)
						(arc
							(start 0.1778 0.2794)
							(mid 0.249642 0.249642)
							(end 0.2794 0.1778)
						)
						(arc
							(start 0.2794 -0.1778)
							(mid 0.249642 -0.249642)
							(end 0.1778 -0.2794)
						)
					)
					(width 0)
					(fill yes)
				)
			)
		)
		(pad "2" smd custom
			(at 0 0.4445 270)
			(size 0.1397 0.1397)
			(layers "F.Cu" "F.Mask" "F.Paste")
			(net "SDA_DR4")
			(options
				(clearance outline)
				(anchor circle)
			)
			(primitives
				(gr_poly
					(pts
						(arc
							(start -0.1778 -0.2794)
							(mid -0.249642 -0.249642)
							(end -0.2794 -0.1778)
						)
						(arc
							(start -0.2794 0.1778)
							(mid -0.249642 0.249642)
							(end -0.1778 0.2794)
						)
						(arc
							(start 0.1778 0.2794)
							(mid 0.249642 0.249642)
							(end 0.2794 0.1778)
						)
						(arc
							(start 0.2794 -0.1778)
							(mid 0.249642 -0.249642)
							(end 0.1778 -0.2794)
						)
					)
					(width 0)
					(fill yes)
				)
			)
		)
	)
	(footprint ""
		(layer "F.Cu")
		(at 37.0586 -418.8714 180)
		(property "Reference" "C392"
			(at 0 0 180)
			(layer "F.SilkS")
			(hide yes)
			(effects
				(font
					(size 1.27 1.27)
				)
			)
		)
		(property "Value" "SCD1U25V2KX-2-GP"
			(at 1.1811 -2.7051 180)
			(unlocked yes)
			(layer "F.Fab")
			(hide yes)
			(effects
				(font
					(size 1.016 1.016)
					(thickness 0.1524)
				)
			)
		)
		(property "Device Type" "C402H22"
			(at 1.1811 -4.2291 180)
			(unlocked yes)
			(layer "F.Fab")
			(hide yes)
			(effects
				(font
					(size 1.016 1.016)
					(thickness 0.1524)
				)
			)
		)
		(duplicate_pad_numbers_are_jumpers no)
		(fp_rect
			(start -0.4318 0.9525)
			(end 0.4318 -0.9525)
			(stroke
				(width 0)
				(type default)
			)
			(fill no)
			(layer "F.CrtYd")
		)
		(fp_rect
			(start -0.4318 0.9525)
			(end 0.4318 -0.9525)
			(stroke
				(width 0)
				(type default)
			)
			(fill no)
			(layer "F.Fab")
		)
		(pad "1" smd custom
			(at 0 -0.4445 180)
			(size 0.1524 0.1524)
			(layers "F.Cu" "F.Mask" "F.Paste")
			(net "P12V")
			(options
				(clearance outline)
				(anchor circle)
			)
			(primitives
				(gr_poly
					(pts
						(arc
							(start 0.3048 -0.2032)
							(mid 0.275042 -0.275042)
							(end 0.2032 -0.3048)
						)
						(arc
							(start -0.2032 -0.3048)
							(mid -0.275042 -0.275042)
							(end -0.3048 -0.2032)
						)
						(arc
							(start -0.3048 0.2032)
							(mid -0.275042 0.275042)
							(end -0.2032 0.3048)
						)
						(arc
							(start 0.2032 0.3048)
							(mid 0.275042 0.275042)
							(end 0.3048 0.2032)
						)
					)
					(width 0)
					(fill yes)
				)
			)
		)
		(pad "2" smd custom
			(at 0 0.4445 180)
			(size 0.1524 0.1524)
			(layers "F.Cu" "F.Mask" "F.Paste")
			(net "SW_SSD10_N")
			(options
				(clearance outline)
				(anchor circle)
			)
			(primitives
				(gr_poly
					(pts
						(arc
							(start 0.3048 -0.2032)
							(mid 0.275042 -0.275042)
							(end 0.2032 -0.3048)
						)
						(arc
							(start -0.2032 -0.3048)
							(mid -0.275042 -0.275042)
							(end -0.3048 -0.2032)
						)
						(arc
							(start -0.3048 0.2032)
							(mid -0.275042 0.275042)
							(end -0.2032 0.3048)
						)
						(arc
							(start 0.2032 0.3048)
							(mid 0.275042 0.275042)
							(end 0.3048 0.2032)
						)
					)
					(width 0)
					(fill yes)
				)
			)
		)
	)
	(footprint ""
		(layer "F.Cu")
		(at 208.534 -197.231)
		(property "Reference" "R9763"
			(at 0 0 0)
			(layer "F.SilkS")
			(hide yes)
			(effects
				(font
					(size 1.27 1.27)
				)
			)
		)
		(property "Value" "4K7R2J-2-GP"
			(at 0.064008 -3.993896 0)
			(unlocked yes)
			(layer "F.Fab")
			(hide yes)
			(effects
				(font
					(size 1.016 1.016)
					(thickness 0.1524)
				)
			)
		)
		(property "Device Type" "R402H16"
			(at 0.064008 -5.517896 0)
			(unlocked yes)
			(layer "F.Fab")
			(hide yes)
			(effects
				(font
					(size 1.016 1.016)
					(thickness 0.1524)
				)
			)
		)
		(duplicate_pad_numbers_are_jumpers no)
		(fp_line
			(start -0.508 -0.9398)
			(end -0.508 0.9398)
			(stroke
				(width 0.1524)
				(type default)
			)
			(layer "F.SilkS")
		)
		(fp_line
			(start 0.508 -0.9398)
			(end -0.508 -0.9398)
			(stroke
				(width 0.1524)
				(type default)
			)
			(layer "F.SilkS")
		)
		(fp_rect
			(start -0.508 0.9398)
			(end 0.508 -0.9398)
			(stroke
				(width 0)
				(type default)
			)
			(fill no)
			(layer "F.CrtYd")
		)
		(fp_rect
			(start -0.508 0.9398)
			(end 0.508 -0.9398)
			(stroke
				(width 0)
				(type default)
			)
			(fill no)
			(layer "F.Fab")
		)
		(pad "1" smd custom
			(at 0 -0.4445)
			(size 0.1397 0.1397)
			(layers "F.Cu" "F.Mask" "F.Paste")
			(net "SSD3_PWREN")
			(options
				(clearance outline)
				(anchor circle)
			)
			(primitives
				(gr_poly
					(pts
						(arc
							(start -0.1778 -0.2794)
							(mid -0.249642 -0.249642)
							(end -0.2794 -0.1778)
						)
						(arc
							(start -0.2794 0.1778)
							(mid -0.249642 0.249642)
							(end -0.1778 0.2794)
						)
						(arc
							(start 0.1778 0.2794)
							(mid 0.249642 0.249642)
							(end 0.2794 0.1778)
						)
						(arc
							(start 0.2794 -0.1778)
							(mid 0.249642 -0.249642)
							(end 0.1778 -0.2794)
						)
					)
					(width 0)
					(fill yes)
				)
			)
		)
		(pad "2" smd custom
			(at 0 0.4445)
			(size 0.1397 0.1397)
			(layers "F.Cu" "F.Mask" "F.Paste")
			(net "GND")
			(options
				(clearance outline)
				(anchor circle)
			)
			(primitives
				(gr_poly
					(pts
						(arc
							(start -0.1778 -0.2794)
							(mid -0.249642 -0.249642)
							(end -0.2794 -0.1778)
						)
						(arc
							(start -0.2794 0.1778)
							(mid -0.249642 0.249642)
							(end -0.1778 0.2794)
						)
						(arc
							(start 0.1778 0.2794)
							(mid 0.249642 0.249642)
							(end 0.2794 0.1778)
						)
						(arc
							(start 0.2794 -0.1778)
							(mid 0.249642 -0.249642)
							(end 0.1778 -0.2794)
						)
					)
					(width 0)
					(fill yes)
				)
			)
		)
	)
	(footprint ""
		(layer "F.Cu")
		(at 20.16125 -401.79625 180)
		(property "Reference" "R9516"
			(at 0 0 180)
			(layer "F.SilkS")
			(hide yes)
			(effects
				(font
					(size 1.27 1.27)
				)
			)
		)
		(property "Value" "4K7R2J-2-GP"
			(at 0.064008 -3.993896 180)
			(unlocked yes)
			(layer "F.Fab")
			(hide yes)
			(effects
				(font
					(size 1.016 1.016)
					(thickness 0.1524)
				)
			)
		)
		(property "Device Type" "R402H16"
			(at 0.064008 -5.517896 180)
			(unlocked yes)
			(layer "F.Fab")
			(hide yes)
			(effects
				(font
					(size 1.016 1.016)
					(thickness 0.1524)
				)
			)
		)
		(duplicate_pad_numbers_are_jumpers no)
		(fp_line
			(start 0.508 -0.9398)
			(end -0.508 -0.9398)
			(stroke
				(width 0.1524)
				(type default)
			)
			(layer "F.SilkS")
		)
		(fp_line
			(start -0.508 -0.9398)
			(end -0.508 0.9398)
			(stroke
				(width 0.1524)
				(type default)
			)
			(layer "F.SilkS")
		)
		(fp_rect
			(start -0.508 0.9398)
			(end 0.508 -0.9398)
			(stroke
				(width 0)
				(type default)
			)
			(fill no)
			(layer "F.CrtYd")
		)
		(fp_rect
			(start -0.508 0.9398)
			(end 0.508 -0.9398)
			(stroke
				(width 0)
				(type default)
			)
			(fill no)
			(layer "F.Fab")
		)
		(pad "1" smd custom
			(at 0 -0.4445 180)
			(size 0.1397 0.1397)
			(layers "F.Cu" "F.Mask" "F.Paste")
			(net "P3V3")
			(options
				(clearance outline)
				(anchor circle)
			)
			(primitives
				(gr_poly
					(pts
						(arc
							(start -0.1778 -0.2794)
							(mid -0.249642 -0.249642)
							(end -0.2794 -0.1778)
						)
						(arc
							(start -0.2794 0.1778)
							(mid -0.249642 0.249642)
							(end -0.1778 0.2794)
						)
						(arc
							(start 0.1778 0.2794)
							(mid 0.249642 0.249642)
							(end 0.2794 0.1778)
						)
						(arc
							(start 0.2794 -0.1778)
							(mid 0.249642 -0.249642)
							(end 0.1778 -0.2794)
						)
					)
					(width 0)
					(fill yes)
				)
			)
		)
		(pad "2" smd custom
			(at 0 0.4445 180)
			(size 0.1397 0.1397)
			(layers "F.Cu" "F.Mask" "F.Paste")
			(net "SSD6_PWREN")
			(options
				(clearance outline)
				(anchor circle)
			)
			(primitives
				(gr_poly
					(pts
						(arc
							(start -0.1778 -0.2794)
							(mid -0.249642 -0.249642)
							(end -0.2794 -0.1778)
						)
						(arc
							(start -0.2794 0.1778)
							(mid -0.249642 0.249642)
							(end -0.1778 0.2794)
						)
						(arc
							(start 0.1778 0.2794)
							(mid 0.249642 0.249642)
							(end 0.2794 0.1778)
						)
						(arc
							(start 0.2794 -0.1778)
							(mid 0.249642 -0.249642)
							(end 0.1778 -0.2794)
						)
					)
					(width 0)
					(fill yes)
				)
			)
		)
	)
)
